# S9S_MB_2U (Grand Teton) — schematic netlist excerpt (pin names and nets, part order shuffled) for the footprints in the layout excerpt that follows; sources: Cadence DE-HDL packaged netlist, KiCad conversion of 03242023_DA0F0TMBIJ0_F0T_Motherboard_J_brd_V01_OCP.brd

X1  TP_TDR_4P_FTS  TP_TDR_4P_DIP EMPTY  pkg TH  page 309
  S1  = TDR_DIFF_85_TOP_DP
  P1  = T1_GND
  P2  = T1_GND
  S2  = TDR_DIFF_85_TOP_DN

C2007  Q_CAP  1UF 25V 10% X6S  pkg C0402  page 190 : A = P3V3_AUX ; B = GND

(kicad_pcb
	(version 20260206)
	(generator "pcbnew")
	(generator_version "10.0")
	(general
		(thickness 1.6)
		(legacy_teardrops no)
	)
	(paper "A4")
	(title_block
		(title "03242023_DA0F0TMBIJ0_F0T_Motherboard_J_brd_V01_OCP.brd")
		(comment 1 "Grand Teton / footprints 3062-3063 of 6105")
	)
	(layers
		(0 "F.Cu" signal "TOP")
		(4 "In1.Cu" signal "GND")
		(6 "In2.Cu" signal "IN1")
		(8 "In3.Cu" signal "GND1")
		(10 "In4.Cu" signal "IN2")
		(12 "In5.Cu" signal "GND2")
		(14 "In6.Cu" signal "IN3")
		(16 "In7.Cu" signal "GND3")
		(18 "In8.Cu" signal "VCC")
		(20 "In9.Cu" signal "VCC1")
		(22 "In10.Cu" signal "GND4")
		(24 "In11.Cu" signal "IN4")
		(26 "In12.Cu" signal "GND5")
		(28 "In13.Cu" signal "IN5")
		(30 "In14.Cu" signal "GND6")
		(32 "In15.Cu" signal "IN6")
		(34 "In16.Cu" signal "GND7")
		(2 "B.Cu" signal "BOTTOM")
		(9 "F.Adhes" user "F.Adhesive")
		(11 "B.Adhes" user "B.Adhesive")
		(13 "F.Paste" user "Package Geometry/Pastemask Top")
		(15 "B.Paste" user "Package Geometry/Pastemask Bottom")
		(5 "F.SilkS" user "Ref Des/Silkscreen Top")
		(7 "B.SilkS" user "Ref Des/Silkscreen Bottom")
		(1 "F.Mask" user "Board Geometry/Soldermask Top")
		(3 "B.Mask" user "Board Geometry/Soldermask Bottom")
		(17 "Dwgs.User" user "User.Drawings")
		(19 "Cmts.User" user "User.Comments")
		(21 "Eco1.User" user "User.Eco1")
		(23 "Eco2.User" user "User.Eco2")
		(25 "Edge.Cuts" user "Board Geometry/Outline")
		(27 "Margin" user)
		(31 "F.CrtYd" user "Package Geometry/Place Bound Top")
		(29 "B.CrtYd" user "Package Geometry/Place Bound Bottom")
		(35 "F.Fab" user "Ref Des/Assembly Top")
		(33 "B.Fab" user "Ref Des/Assembly Bottom")
	)
	(footprint ""
		(layer "F.Cu")
		(at 140.39088 -42.255948 90)
		(property "Reference" "C2007"
			(at 0 0 90)
			(layer "F.SilkS")
			(hide yes)
			(effects
				(font
					(size 1.27 1.27)
				)
			)
		)
		(property "Value" ""
			(at 0 0 90)
			(layer "F.Fab")
			(effects
				(font
					(size 1.27 1.27)
				)
			)
		)
		(duplicate_pad_numbers_are_jumpers no)
		(fp_line
			(start 0.7874 -0.4064)
			(end 0.7874 0.4064)
			(stroke
				(width 0.1524)
				(type default)
			)
			(layer "F.SilkS")
		)
		(fp_line
			(start -0.7874 -0.4064)
			(end 0.7874 -0.4064)
			(stroke
				(width 0.1524)
				(type default)
			)
			(layer "F.SilkS")
		)
		(fp_line
			(start 0.7874 0.4064)
			(end -0.7874 0.4064)
			(stroke
				(width 0.1524)
				(type default)
			)
			(layer "F.SilkS")
		)
		(fp_line
			(start -0.7874 0.4064)
			(end -0.7874 -0.4064)
			(stroke
				(width 0.1524)
				(type default)
			)
			(layer "F.SilkS")
		)
		(fp_line
			(start -0.12065 -0.305054)
			(end -0.12065 -0.2794)
			(stroke
				(width 0.1)
				(type default)
			)
			(layer "F.Fab")
		)
		(fp_line
			(start -0.67945 -0.305054)
			(end -0.12065 -0.305054)
			(stroke
				(width 0.1)
				(type default)
			)
			(layer "F.Fab")
		)
		(fp_line
			(start 0.67945 -0.3048)
			(end 0.67945 0.3048)
			(stroke
				(width 0.1)
				(type default)
			)
			(layer "F.Fab")
		)
		(fp_line
			(start 0.12065 -0.3048)
			(end 0.67945 -0.3048)
			(stroke
				(width 0.1)
				(type default)
			)
			(layer "F.Fab")
		)
		(fp_line
			(start 0.12065 -0.2794)
			(end 0.12065 -0.3048)
			(stroke
				(width 0.1)
				(type default)
			)
			(layer "F.Fab")
		)
		(fp_line
			(start -0.12065 -0.2794)
			(end 0.12065 -0.2794)
			(stroke
				(width 0.1)
				(type default)
			)
			(layer "F.Fab")
		)
		(fp_line
			(start 0.120396 0.2794)
			(end -0.12065 0.2794)
			(stroke
				(width 0.1)
				(type default)
			)
			(layer "F.Fab")
		)
		(fp_line
			(start -0.12065 0.2794)
			(end -0.12065 0.3048)
			(stroke
				(width 0.1)
				(type default)
			)
			(layer "F.Fab")
		)
		(fp_line
			(start 0.67945 0.3048)
			(end 0.120396 0.3048)
			(stroke
				(width 0.1)
				(type default)
			)
			(layer "F.Fab")
		)
		(fp_line
			(start 0.120396 0.3048)
			(end 0.120396 0.2794)
			(stroke
				(width 0.1)
				(type default)
			)
			(layer "F.Fab")
		)
		(fp_line
			(start -0.12065 0.3048)
			(end -0.67945 0.3048)
			(stroke
				(width 0.1)
				(type default)
			)
			(layer "F.Fab")
		)
		(fp_line
			(start -0.67945 0.3048)
			(end -0.67945 -0.305054)
			(stroke
				(width 0.1)
				(type default)
			)
			(layer "F.Fab")
		)
		(pad "1" smd circle
			(at -0.40005 0 90)
			(size 0 0)
			(layers "F.Cu" "F.Mask" "F.Paste")
			(net "P3V3_AUX")
		)
		(pad "2" smd circle
			(at 0.40005 0 90)
			(size 0 0)
			(layers "F.Cu" "F.Mask" "F.Paste")
			(net "GND")
		)
	)
	(footprint ""
		(layer "F.Cu")
		(at 525.408906 -303.624488 90)
		(property "Reference" "X1"
			(at -2.594864 3.123184 90)
			(unlocked yes)
			(layer "F.SilkS")
			(effects
				(font
					(size 0.7874 0.5842)
					(thickness 0.1524)
				)
				(justify left)
			)
		)
		(property "Value" ""
			(at 0 0 90)
			(layer "F.Fab")
			(effects
				(font
					(size 1.27 1.27)
				)
			)
		)
		(property "Device Type" "TP_TDR_4P_FTS_TH-TP_TDR_4P_DIPA"
			(at 1.30175 1.27 180)
			(unlocked yes)
			(layer "F.Fab")
			(hide yes)
			(effects
				(font
					(size 0.635 0.4064)
					(thickness 0.1524)
				)
			)
		)
		(property "User Part Number" "N_A"
			(at 1.30175 1.27 180)
			(unlocked yes)
			(layer "Cmts.User")
			(hide yes)
			(effects
				(font
					(size 0.635 0.4064)
					(thickness 0.1524)
				)
			)
		)
		(duplicate_pad_numbers_are_jumpers no)
		(fp_line
			(start 2.54 -1.27)
			(end 0 -1.27)
			(stroke
				(width 0.1524)
				(type default)
			)
			(layer "F.SilkS")
		)
		(fp_line
			(start 0 -1.27)
			(end 0 -0.635)
			(stroke
				(width 0.1524)
				(type default)
			)
			(layer "F.SilkS")
		)
		(fp_line
			(start 2.54 -1.1303)
			(end 2.54 -1.27)
			(stroke
				(width 0.1524)
				(type default)
			)
			(layer "F.SilkS")
		)
		(fp_line
			(start 0 0.635)
			(end 0 1.905)
			(stroke
				(width 0.1524)
				(type default)
			)
			(layer "F.SilkS")
		)
		(fp_line
			(start 2.54 1.4097)
			(end 2.54 1.1303)
			(stroke
				(width 0.1524)
				(type default)
			)
			(layer "F.SilkS")
		)
		(fp_line
			(start 0 3.175)
			(end 0 3.81)
			(stroke
				(width 0.1524)
				(type default)
			)
			(layer "F.SilkS")
		)
		(fp_line
			(start 2.54 3.81)
			(end 2.54 3.6703)
			(stroke
				(width 0.1524)
				(type default)
			)
			(layer "F.SilkS")
		)
		(fp_line
			(start 0 3.81)
			(end 2.54 3.81)
			(stroke
				(width 0.1524)
				(type default)
			)
			(layer "F.SilkS")
		)
		(fp_poly
			(pts
				(xy -0.761746 0) (xy -2.285746 0.762) (xy -2.285746 -0.762)
			)
			(stroke
				(width 0)
				(type default)
			)
			(fill yes)
			(layer "F.SilkS")
		)
		(fp_line
			(start 2.54 -1.27)
			(end 0 -1.27)
			(stroke
				(width 0.1)
				(type default)
			)
			(layer "F.Fab")
		)
		(fp_line
			(start 0 -1.27)
			(end 0 3.81)
			(stroke
				(width 0.1)
				(type default)
			)
			(layer "F.Fab")
		)
		(fp_line
			(start 2.54 3.81)
			(end 2.54 -1.27)
			(stroke
				(width 0.1)
				(type default)
			)
			(layer "F.Fab")
		)
		(fp_line
			(start 0 3.81)
			(end 2.54 3.81)
			(stroke
				(width 0.1)
				(type default)
			)
			(layer "F.Fab")
		)
		(fp_poly
			(pts
				(xy -0.761746 0) (xy -2.285746 -0.762) (xy -2.285746 0.762)
			)
			(stroke
				(width 0)
				(type default)
			)
			(fill yes)
			(layer "F.Fab")
		)
		(pad "1" thru_hole circle
			(at 0 0 90)
			(size 1.0033 1.0033)
			(drill 0.249936)
			(layers "*.Cu" "*.Mask")
			(remove_unused_layers no)
			(net "TDR_DIFF_85_TOP_DP")
			(clearance 0.10795)
			(thermal_gap 0.10795)
			(padstack
				(mode front_inner_back)
				(layer "Inner"
					(shape circle)
					(size 0.8001 0.8001)
					(clearance 0.1524)
				)
				(layer "B.Cu"
					(shape circle)
					(size 1.0033 1.0033)
					(clearance 0.10795)
				)
			)
		)
		(pad "2" thru_hole circle
			(at 2.54 0 90)
			(size 1.9939 1.9939)
			(drill 0.249936)
			(layers "*.Cu" "*.Mask")
			(remove_unused_layers no)
			(net "T1_GND")
			(clearance 0.10795)
			(thermal_gap 0.10795)
			(padstack
				(mode front_inner_back)
				(layer "Inner"
					(shape circle)
					(size 0.8001 0.8001)
					(clearance 0.1524)
				)
				(layer "B.Cu"
					(shape circle)
					(size 1.9939 1.9939)
					(clearance 0.10795)
				)
			)
		)
		(pad "3" thru_hole circle
			(at 2.54 2.54 90)
			(size 1.9939 1.9939)
			(drill 0.249936)
			(layers "*.Cu" "*.Mask")
			(remove_unused_layers no)
			(net "T1_GND")
			(clearance 0.10795)
			(thermal_gap 0.10795)
			(padstack
				(mode front_inner_back)
				(layer "Inner"
					(shape circle)
					(size 0.8001 0.8001)
					(clearance 0.1524)
				)
				(layer "B.Cu"
					(shape circle)
					(size 1.9939 1.9939)
					(clearance 0.10795)
				)
			)
		)
		(pad "4" thru_hole circle
			(at 0 2.54 90)
			(size 1.0033 1.0033)
			(drill 0.249936)
			(layers "*.Cu" "*.Mask")
			(remove_unused_layers no)
			(net "TDR_DIFF_85_TOP_DN")
			(clearance 0.10795)
			(thermal_gap 0.10795)
			(padstack
				(mode front_inner_back)
				(layer "Inner"
					(shape circle)
					(size 0.8001 0.8001)
					(clearance 0.1524)
				)
				(layer "B.Cu"
					(shape circle)
					(size 1.0033 1.0033)
					(clearance 0.10795)
				)
			)
		)
	)
)
